(kicad_pcb
	(version 20260206)
	(generator "pcbnew")
	(generator_version "10.0")
	(general
		(thickness 1.6)
		(legacy_teardrops no)
	)
	(paper "A4")
	(title_block
		(title "Bryce Canyon_SCC_16316-1_OCP.brd")
		(comment 1 "Bryce Canyon / footprints 895-902 of 1561")
	)
	(layers
		(0 "F.Cu" signal "TOP")
		(4 "In1.Cu" signal "L2GND")
		(6 "In2.Cu" signal "L3")
		(8 "In3.Cu" signal "L4VCC")
		(10 "In4.Cu" signal "L5VCC")
		(12 "In5.Cu" signal "L6")
		(14 "In6.Cu" signal "L7GND")
		(2 "B.Cu" signal "BOTTOM")
		(9 "F.Adhes" user "F.Adhesive")
		(11 "B.Adhes" user "B.Adhesive")
		(13 "F.Paste" user "Package Geometry/Pastemask Top")
		(15 "B.Paste" user "Package Geometry/Pastemask Bottom")
		(5 "F.SilkS" user "Ref Des/Silkscreen Top")
		(7 "B.SilkS" user "Ref Des/Silkscreen Bottom")
		(1 "F.Mask" user "Board Geometry/Soldermask Top")
		(3 "B.Mask" user "Board Geometry/Soldermask Bottom")
		(17 "Dwgs.User" user "User.Drawings")
		(19 "Cmts.User" user "User.Comments")
		(21 "Eco1.User" user "User.Eco1")
		(23 "Eco2.User" user "User.Eco2")
		(25 "Edge.Cuts" user "Board Geometry/Outline")
		(27 "Margin" user)
		(31 "F.CrtYd" user "Package Geometry/Place Bound Top")
		(29 "B.CrtYd" user "Package Geometry/Place Bound Bottom")
		(35 "F.Fab" user "Ref Des/Assembly Top")
		(33 "B.Fab" user "Ref Des/Assembly Bottom")
	)
	(footprint ""
		(layer "B.Cu")
		(at 173.625002 -20.88642)
		(property "Reference" "C320"
			(at 0 0 0)
			(layer "B.SilkS")
			(hide yes)
			(effects
				(font
					(size 1.27 1.27)
				)
				(justify mirror)
			)
		)
		(property "Value" "SCD22U10V1KX-GP"
			(at 2.8321 -1.7399 0)
			(unlocked yes)
			(layer "B.Fab")
			(hide yes)
			(effects
				(font
					(size 1.016 1.016)
					(thickness 0.1524)
				)
				(justify mirror)
			)
		)
		(property "Device Type" "C0201H13"
			(at 2.8321 -3.2639 0)
			(unlocked yes)
			(layer "B.Fab")
			(hide yes)
			(effects
				(font
					(size 1.016 1.016)
					(thickness 0.1524)
				)
				(justify mirror)
			)
		)
		(duplicate_pad_numbers_are_jumpers no)
		(fp_rect
			(start 0.2794 0.6477)
			(end -0.2794 -0.6477)
			(stroke
				(width 0)
				(type default)
			)
			(fill no)
			(layer "B.CrtYd")
		)
		(fp_rect
			(start 0.2794 0.6477)
			(end -0.2794 -0.6477)
			(stroke
				(width 0)
				(type default)
			)
			(fill no)
			(layer "B.Fab")
		)
		(pad "1" smd custom
			(at 0 -0.2794 180)
			(size 0.0762 0.0762)
			(layers "B.Cu" "B.Mask" "B.Paste")
			(net "PCIE_SCC_TO_COMP_C_4_DN")
			(options
				(clearance outline)
				(anchor circle)
			)
			(primitives
				(gr_poly
					(pts
						(arc
							(start 0.1524 0.127)
							(mid 0.137521 0.162921)
							(end 0.1016 0.1778)
						)
						(arc
							(start -0.1016 0.1778)
							(mid -0.137521 0.162921)
							(end -0.1524 0.127)
						)
						(arc
							(start -0.1524 -0.127)
							(mid -0.137521 -0.162921)
							(end -0.1016 -0.1778)
						)
						(arc
							(start 0.1016 -0.1778)
							(mid 0.137521 -0.162921)
							(end 0.1524 -0.127)
						)
					)
					(width 0)
					(fill yes)
				)
			)
		)
		(pad "2" smd custom
			(at 0 0.2794 180)
			(size 0.0762 0.0762)
			(layers "B.Cu" "B.Mask" "B.Paste")
			(net "PCIE_SCC_TO_COMP_4_DN")
			(options
				(clearance outline)
				(anchor circle)
			)
			(primitives
				(gr_poly
					(pts
						(arc
							(start 0.1524 0.127)
							(mid 0.137521 0.162921)
							(end 0.1016 0.1778)
						)
						(arc
							(start -0.1016 0.1778)
							(mid -0.137521 0.162921)
							(end -0.1524 0.127)
						)
						(arc
							(start -0.1524 -0.127)
							(mid -0.137521 -0.162921)
							(end -0.1016 -0.1778)
						)
						(arc
							(start 0.1016 -0.1778)
							(mid 0.137521 -0.162921)
							(end 0.1524 -0.127)
						)
					)
					(width 0)
					(fill yes)
				)
			)
		)
	)
	(footprint ""
		(layer "B.Cu")
		(at 157.867604 -64.122808 90)
		(property "Reference" "C359"
			(at 0 0 90)
			(layer "B.SilkS")
			(hide yes)
			(effects
				(font
					(size 1.27 1.27)
				)
				(justify mirror)
			)
		)
		(property "Value" "SC22U6D3V3MX-9-GP-U"
			(at 0 -2.8194 90)
			(unlocked yes)
			(layer "B.Fab")
			(hide yes)
			(effects
				(font
					(size 1.016 1.016)
					(thickness 0.1524)
				)
				(justify mirror)
			)
		)
		(property "Device Type" "C603H40"
			(at 0 -4.3434 90)
			(unlocked yes)
			(layer "B.Fab")
			(hide yes)
			(effects
				(font
					(size 1.016 1.016)
					(thickness 0.1524)
				)
				(justify mirror)
			)
		)
		(duplicate_pad_numbers_are_jumpers no)
		(fp_line
			(start -0.508 0)
			(end 0.508 0)
			(stroke
				(width 0.2032)
				(type default)
			)
			(layer "B.SilkS")
		)
		(fp_rect
			(start 0.5842 1.3335)
			(end -0.5842 -1.3335)
			(stroke
				(width 0)
				(type default)
			)
			(fill no)
			(layer "B.CrtYd")
		)
		(fp_rect
			(start 0.5842 1.3335)
			(end -0.5842 -1.3335)
			(stroke
				(width 0)
				(type default)
			)
			(fill no)
			(layer "B.Fab")
		)
		(pad "1" smd custom
			(at 0 -0.762 270)
			(size 0.2159 0.2159)
			(layers "B.Cu" "B.Mask" "B.Paste")
			(net "SHELL_PLL_VDD")
			(options
				(clearance outline)
				(anchor circle)
			)
			(primitives
				(gr_poly
					(pts
						(arc
							(start -0.3302 0.4318)
							(mid -0.402042 0.402042)
							(end -0.4318 0.3302)
						)
						(arc
							(start -0.4318 -0.3302)
							(mid -0.402042 -0.402042)
							(end -0.3302 -0.4318)
						)
						(arc
							(start 0.3302 -0.4318)
							(mid 0.402042 -0.402042)
							(end 0.4318 -0.3302)
						)
						(arc
							(start 0.4318 0.3302)
							(mid 0.402042 0.402042)
							(end 0.3302 0.4318)
						)
					)
					(width 0)
					(fill yes)
				)
			)
		)
		(pad "2" smd custom
			(at 0 0.762 270)
			(size 0.2159 0.2159)
			(layers "B.Cu" "B.Mask" "B.Paste")
			(net "GND")
			(options
				(clearance outline)
				(anchor circle)
			)
			(primitives
				(gr_poly
					(pts
						(arc
							(start -0.3302 0.4318)
							(mid -0.402042 0.402042)
							(end -0.4318 0.3302)
						)
						(arc
							(start -0.4318 -0.3302)
							(mid -0.402042 -0.402042)
							(end -0.3302 -0.4318)
						)
						(arc
							(start 0.3302 -0.4318)
							(mid 0.402042 -0.402042)
							(end 0.4318 -0.3302)
						)
						(arc
							(start 0.4318 0.3302)
							(mid 0.402042 0.402042)
							(end 0.3302 0.4318)
						)
					)
					(width 0)
					(fill yes)
				)
			)
		)
	)
	(footprint ""
		(layer "B.Cu")
		(at 118.6307 -57.4802)
		(property "Reference" "C238"
			(at 0 0 0)
			(layer "B.SilkS")
			(hide yes)
			(effects
				(font
					(size 1.27 1.27)
				)
				(justify mirror)
			)
		)
		(property "Value" "SCD1U6D3V1KX-GP"
			(at 2.8321 -1.7399 0)
			(unlocked yes)
			(layer "B.Fab")
			(hide yes)
			(effects
				(font
					(size 1.016 1.016)
					(thickness 0.1524)
				)
				(justify mirror)
			)
		)
		(property "Device Type" "C0201H13"
			(at 2.8321 -3.2639 0)
			(unlocked yes)
			(layer "B.Fab")
			(hide yes)
			(effects
				(font
					(size 1.016 1.016)
					(thickness 0.1524)
				)
				(justify mirror)
			)
		)
		(duplicate_pad_numbers_are_jumpers no)
		(fp_rect
			(start 0.2794 0.6477)
			(end -0.2794 -0.6477)
			(stroke
				(width 0)
				(type default)
			)
			(fill no)
			(layer "B.CrtYd")
		)
		(fp_rect
			(start 0.2794 0.6477)
			(end -0.2794 -0.6477)
			(stroke
				(width 0)
				(type default)
			)
			(fill no)
			(layer "B.Fab")
		)
		(pad "1" smd custom
			(at 0 -0.2794 180)
			(size 0.0762 0.0762)
			(layers "B.Cu" "B.Mask" "B.Paste")
			(net "GB_VDDA")
			(options
				(clearance outline)
				(anchor circle)
			)
			(primitives
				(gr_poly
					(pts
						(arc
							(start 0.1524 0.127)
							(mid 0.137521 0.162921)
							(end 0.1016 0.1778)
						)
						(arc
							(start -0.1016 0.1778)
							(mid -0.137521 0.162921)
							(end -0.1524 0.127)
						)
						(arc
							(start -0.1524 -0.127)
							(mid -0.137521 -0.162921)
							(end -0.1016 -0.1778)
						)
						(arc
							(start 0.1016 -0.1778)
							(mid 0.137521 -0.162921)
							(end 0.1524 -0.127)
						)
					)
					(width 0)
					(fill yes)
				)
			)
		)
		(pad "2" smd custom
			(at 0 0.2794 180)
			(size 0.0762 0.0762)
			(layers "B.Cu" "B.Mask" "B.Paste")
			(net "GND")
			(options
				(clearance outline)
				(anchor circle)
			)
			(primitives
				(gr_poly
					(pts
						(arc
							(start 0.1524 0.127)
							(mid 0.137521 0.162921)
							(end 0.1016 0.1778)
						)
						(arc
							(start -0.1016 0.1778)
							(mid -0.137521 0.162921)
							(end -0.1524 0.127)
						)
						(arc
							(start -0.1524 -0.127)
							(mid -0.137521 -0.162921)
							(end -0.1016 -0.1778)
						)
						(arc
							(start 0.1016 -0.1778)
							(mid 0.137521 -0.162921)
							(end 0.1524 -0.127)
						)
					)
					(width 0)
					(fill yes)
				)
			)
		)
	)
	(footprint ""
		(layer "B.Cu")
		(at 124.2822 -65.5066 -90)
		(property "Reference" "C578"
			(at 0 0 90)
			(layer "B.SilkS")
			(hide yes)
			(effects
				(font
					(size 1.27 1.27)
				)
				(justify mirror)
			)
		)
		(property "Value" "SCD1U6D3V1KX-GP"
			(at 2.8321 -1.7399 270)
			(unlocked yes)
			(layer "B.Fab")
			(hide yes)
			(effects
				(font
					(size 1.016 1.016)
					(thickness 0.1524)
				)
				(justify mirror)
			)
		)
		(property "Device Type" "C0201H13"
			(at 2.8321 -3.2639 270)
			(unlocked yes)
			(layer "B.Fab")
			(hide yes)
			(effects
				(font
					(size 1.016 1.016)
					(thickness 0.1524)
				)
				(justify mirror)
			)
		)
		(duplicate_pad_numbers_are_jumpers no)
		(fp_rect
			(start 0.2794 0.6477)
			(end -0.2794 -0.6477)
			(stroke
				(width 0)
				(type default)
			)
			(fill no)
			(layer "B.CrtYd")
		)
		(fp_rect
			(start 0.2794 0.6477)
			(end -0.2794 -0.6477)
			(stroke
				(width 0)
				(type default)
			)
			(fill no)
			(layer "B.Fab")
		)
		(pad "1" smd custom
			(at 0 -0.2794 90)
			(size 0.0762 0.0762)
			(layers "B.Cu" "B.Mask" "B.Paste")
			(net "GB_VDDA")
			(options
				(clearance outline)
				(anchor circle)
			)
			(primitives
				(gr_poly
					(pts
						(arc
							(start 0.1524 0.127)
							(mid 0.137521 0.162921)
							(end 0.1016 0.1778)
						)
						(arc
							(start -0.1016 0.1778)
							(mid -0.137521 0.162921)
							(end -0.1524 0.127)
						)
						(arc
							(start -0.1524 -0.127)
							(mid -0.137521 -0.162921)
							(end -0.1016 -0.1778)
						)
						(arc
							(start 0.1016 -0.1778)
							(mid 0.137521 -0.162921)
							(end 0.1524 -0.127)
						)
					)
					(width 0)
					(fill yes)
				)
			)
		)
		(pad "2" smd custom
			(at 0 0.2794 90)
			(size 0.0762 0.0762)
			(layers "B.Cu" "B.Mask" "B.Paste")
			(net "GND")
			(options
				(clearance outline)
				(anchor circle)
			)
			(primitives
				(gr_poly
					(pts
						(arc
							(start 0.1524 0.127)
							(mid 0.137521 0.162921)
							(end 0.1016 0.1778)
						)
						(arc
							(start -0.1016 0.1778)
							(mid -0.137521 0.162921)
							(end -0.1524 0.127)
						)
						(arc
							(start -0.1524 -0.127)
							(mid -0.137521 -0.162921)
							(end -0.1016 -0.1778)
						)
						(arc
							(start 0.1016 -0.1778)
							(mid 0.137521 -0.162921)
							(end 0.1524 -0.127)
						)
					)
					(width 0)
					(fill yes)
				)
			)
		)
	)
	(footprint ""
		(layer "B.Cu")
		(at 93.951806 -74.788014 180)
		(property "Reference" "C205"
			(at 0 0 0)
			(layer "B.SilkS")
			(hide yes)
			(effects
				(font
					(size 1.27 1.27)
				)
				(justify mirror)
			)
		)
		(property "Value" "SC10U6D3V2MX-GP-U"
			(at 1.524 -1.905 180)
			(unlocked yes)
			(layer "B.Fab")
			(hide yes)
			(effects
				(font
					(size 1.016 1.016)
					(thickness 0.1524)
				)
				(justify mirror)
			)
		)
		(property "Device Type" "C402-TO0D2H28"
			(at 1.524 -3.429 180)
			(unlocked yes)
			(layer "B.Fab")
			(hide yes)
			(effects
				(font
					(size 1.016 1.016)
					(thickness 0.1524)
				)
				(justify mirror)
			)
		)
		(duplicate_pad_numbers_are_jumpers no)
		(fp_rect
			(start 0.4826 0.889)
			(end -0.4826 -0.889)
			(stroke
				(width 0)
				(type default)
			)
			(fill no)
			(layer "B.CrtYd")
		)
		(fp_rect
			(start 0.4826 0.889)
			(end -0.4826 -0.889)
			(stroke
				(width 0)
				(type default)
			)
			(fill no)
			(layer "B.Fab")
		)
		(pad "1" smd custom
			(at 0 -0.4572)
			(size 0.1524 0.1524)
			(layers "B.Cu" "B.Mask" "B.Paste")
			(net "XTAL_VDDA09")
			(options
				(clearance outline)
				(anchor circle)
			)
			(primitives
				(gr_poly
					(pts
						(arc
							(start -0.254 -0.3048)
							(mid -0.325842 -0.275042)
							(end -0.3556 -0.2032)
						)
						(arc
							(start -0.3556 0.2032)
							(mid -0.325842 0.275042)
							(end -0.254 0.3048)
						)
						(arc
							(start 0.254 0.3048)
							(mid 0.325842 0.275042)
							(end 0.3556 0.2032)
						)
						(arc
							(start 0.3556 -0.2032)
							(mid 0.325842 -0.275042)
							(end 0.254 -0.3048)
						)
					)
					(width 0)
					(fill yes)
				)
			)
		)
		(pad "2" smd custom
			(at 0 0.4572)
			(size 0.1524 0.1524)
			(layers "B.Cu" "B.Mask" "B.Paste")
			(net "GND")
			(options
				(clearance outline)
				(anchor circle)
			)
			(primitives
				(gr_poly
					(pts
						(arc
							(start -0.254 -0.3048)
							(mid -0.325842 -0.275042)
							(end -0.3556 -0.2032)
						)
						(arc
							(start -0.3556 0.2032)
							(mid -0.325842 0.275042)
							(end -0.254 0.3048)
						)
						(arc
							(start 0.254 0.3048)
							(mid 0.325842 0.275042)
							(end 0.3556 0.2032)
						)
						(arc
							(start 0.3556 -0.2032)
							(mid 0.325842 -0.275042)
							(end 0.254 -0.3048)
						)
					)
					(width 0)
					(fill yes)
				)
			)
		)
	)
	(footprint ""
		(layer "B.Cu")
		(at 196.953378 -31.926022)
		(property "Reference" "C365"
			(at 0 0 0)
			(layer "B.SilkS")
			(hide yes)
			(effects
				(font
					(size 1.27 1.27)
				)
				(justify mirror)
			)
		)
		(property "Value" "SC1U16V2KX-7-GP"
			(at -1.7526 -1.6002 0)
			(unlocked yes)
			(layer "B.Fab")
			(hide yes)
			(effects
				(font
					(size 1.016 1.016)
					(thickness 0.1524)
				)
				(justify mirror)
			)
		)
		(property "Device Type" "C402-TO0D2H24"
			(at -1.7526 -3.1242 0)
			(unlocked yes)
			(layer "B.Fab")
			(hide yes)
			(effects
				(font
					(size 1.016 1.016)
					(thickness 0.1524)
				)
				(justify mirror)
			)
		)
		(duplicate_pad_numbers_are_jumpers no)
		(fp_rect
			(start 0.4826 0.889)
			(end -0.4826 -0.889)
			(stroke
				(width 0)
				(type default)
			)
			(fill no)
			(layer "B.CrtYd")
		)
		(fp_rect
			(start 0.4826 0.889)
			(end -0.4826 -0.889)
			(stroke
				(width 0)
				(type default)
			)
			(fill no)
			(layer "B.Fab")
		)
		(pad "1" smd custom
			(at 0 -0.4572 180)
			(size 0.1524 0.1524)
			(layers "B.Cu" "B.Mask" "B.Paste")
			(net "PLL_VDD")
			(options
				(clearance outline)
				(anchor circle)
			)
			(primitives
				(gr_poly
					(pts
						(arc
							(start -0.254 -0.3048)
							(mid -0.325842 -0.275042)
							(end -0.3556 -0.2032)
						)
						(arc
							(start -0.3556 0.2032)
							(mid -0.325842 0.275042)
							(end -0.254 0.3048)
						)
						(arc
							(start 0.254 0.3048)
							(mid 0.325842 0.275042)
							(end 0.3556 0.2032)
						)
						(arc
							(start 0.3556 -0.2032)
							(mid 0.325842 -0.275042)
							(end 0.254 -0.3048)
						)
					)
					(width 0)
					(fill yes)
				)
			)
		)
		(pad "2" smd custom
			(at 0 0.4572 180)
			(size 0.1524 0.1524)
			(layers "B.Cu" "B.Mask" "B.Paste")
			(net "GND")
			(options
				(clearance outline)
				(anchor circle)
			)
			(primitives
				(gr_poly
					(pts
						(arc
							(start -0.254 -0.3048)
							(mid -0.325842 -0.275042)
							(end -0.3556 -0.2032)
						)
						(arc
							(start -0.3556 0.2032)
							(mid -0.325842 0.275042)
							(end -0.254 0.3048)
						)
						(arc
							(start 0.254 0.3048)
							(mid 0.325842 0.275042)
							(end 0.3556 0.2032)
						)
						(arc
							(start 0.3556 -0.2032)
							(mid 0.325842 -0.275042)
							(end 0.254 -0.3048)
						)
					)
					(width 0)
					(fill yes)
				)
			)
		)
	)
	(footprint ""
		(layer "B.Cu")
		(at 124.2822 -62.484 -90)
		(property "Reference" "C514"
			(at 0 0 90)
			(layer "B.SilkS")
			(hide yes)
			(effects
				(font
					(size 1.27 1.27)
				)
				(justify mirror)
			)
		)
		(property "Value" "SCD1U6D3V1KX-GP"
			(at 2.8321 -1.7399 270)
			(unlocked yes)
			(layer "B.Fab")
			(hide yes)
			(effects
				(font
					(size 1.016 1.016)
					(thickness 0.1524)
				)
				(justify mirror)
			)
		)
		(property "Device Type" "C0201H13"
			(at 2.8321 -3.2639 270)
			(unlocked yes)
			(layer "B.Fab")
			(hide yes)
			(effects
				(font
					(size 1.016 1.016)
					(thickness 0.1524)
				)
				(justify mirror)
			)
		)
		(duplicate_pad_numbers_are_jumpers no)
		(fp_rect
			(start 0.2794 0.6477)
			(end -0.2794 -0.6477)
			(stroke
				(width 0)
				(type default)
			)
			(fill no)
			(layer "B.CrtYd")
		)
		(fp_rect
			(start 0.2794 0.6477)
			(end -0.2794 -0.6477)
			(stroke
				(width 0)
				(type default)
			)
			(fill no)
			(layer "B.Fab")
		)
		(pad "1" smd custom
			(at 0 -0.2794 90)
			(size 0.0762 0.0762)
			(layers "B.Cu" "B.Mask" "B.Paste")
			(net "GB_VDDA")
			(options
				(clearance outline)
				(anchor circle)
			)
			(primitives
				(gr_poly
					(pts
						(arc
							(start 0.1524 0.127)
							(mid 0.137521 0.162921)
							(end 0.1016 0.1778)
						)
						(arc
							(start -0.1016 0.1778)
							(mid -0.137521 0.162921)
							(end -0.1524 0.127)
						)
						(arc
							(start -0.1524 -0.127)
							(mid -0.137521 -0.162921)
							(end -0.1016 -0.1778)
						)
						(arc
							(start 0.1016 -0.1778)
							(mid 0.137521 -0.162921)
							(end 0.1524 -0.127)
						)
					)
					(width 0)
					(fill yes)
				)
			)
		)
		(pad "2" smd custom
			(at 0 0.2794 90)
			(size 0.0762 0.0762)
			(layers "B.Cu" "B.Mask" "B.Paste")
			(net "GND")
			(options
				(clearance outline)
				(anchor circle)
			)
			(primitives
				(gr_poly
					(pts
						(arc
							(start 0.1524 0.127)
							(mid 0.137521 0.162921)
							(end 0.1016 0.1778)
						)
						(arc
							(start -0.1016 0.1778)
							(mid -0.137521 0.162921)
							(end -0.1524 0.127)
						)
						(arc
							(start -0.1524 -0.127)
							(mid -0.137521 -0.162921)
							(end -0.1016 -0.1778)
						)
						(arc
							(start 0.1016 -0.1778)
							(mid 0.137521 -0.162921)
							(end 0.1524 -0.127)
						)
					)
					(width 0)
					(fill yes)
				)
			)
		)
	)
	(footprint ""
		(layer "B.Cu")
		(at 170.548808 -51.26101 180)
		(property "Reference" "C465"
			(at 0 0 0)
			(layer "B.SilkS")
			(hide yes)
			(effects
				(font
					(size 1.27 1.27)
				)
				(justify mirror)
			)
		)
		(property "Value" "SCD1U6D3V1KX-GP"
			(at 2.8321 -1.7399 180)
			(unlocked yes)
			(layer "B.Fab")
			(hide yes)
			(effects
				(font
					(size 1.016 1.016)
					(thickness 0.1524)
				)
				(justify mirror)
			)
		)
		(property "Device Type" "C0201H13"
			(at 2.8321 -3.2639 180)
			(unlocked yes)
			(layer "B.Fab")
			(hide yes)
			(effects
				(font
					(size 1.016 1.016)
					(thickness 0.1524)
				)
				(justify mirror)
			)
		)
		(duplicate_pad_numbers_are_jumpers no)
		(fp_rect
			(start 0.2794 0.6477)
			(end -0.2794 -0.6477)
			(stroke
				(width 0)
				(type default)
			)
			(fill no)
			(layer "B.CrtYd")
		)
		(fp_rect
			(start 0.2794 0.6477)
			(end -0.2794 -0.6477)
			(stroke
				(width 0)
				(type default)
			)
			(fill no)
			(layer "B.Fab")
		)
		(pad "1" smd custom
			(at 0 -0.2794)
			(size 0.0762 0.0762)
			(layers "B.Cu" "B.Mask" "B.Paste")
			(net "P1V8_C")
			(options
				(clearance outline)
				(anchor circle)
			)
			(primitives
				(gr_poly
					(pts
						(arc
							(start 0.1524 0.127)
							(mid 0.137521 0.162921)
							(end 0.1016 0.1778)
						)
						(arc
							(start -0.1016 0.1778)
							(mid -0.137521 0.162921)
							(end -0.1524 0.127)
						)
						(arc
							(start -0.1524 -0.127)
							(mid -0.137521 -0.162921)
							(end -0.1016 -0.1778)
						)
						(arc
							(start 0.1016 -0.1778)
							(mid 0.137521 -0.162921)
							(end 0.1524 -0.127)
						)
					)
					(width 0)
					(fill yes)
				)
			)
		)
		(pad "2" smd custom
			(at 0 0.2794)
			(size 0.0762 0.0762)
			(layers "B.Cu" "B.Mask" "B.Paste")
			(net "GND")
			(options
				(clearance outline)
				(anchor circle)
			)
			(primitives
				(gr_poly
					(pts
						(arc
							(start 0.1524 0.127)
							(mid 0.137521 0.162921)
							(end 0.1016 0.1778)
						)
						(arc
							(start -0.1016 0.1778)
							(mid -0.137521 0.162921)
							(end -0.1524 0.127)
						)
						(arc
							(start -0.1524 -0.127)
							(mid -0.137521 -0.162921)
							(end -0.1016 -0.1778)
						)
						(arc
							(start 0.1016 -0.1778)
							(mid 0.137521 -0.162921)
							(end 0.1524 -0.127)
						)
					)
					(width 0)
					(fill yes)
				)
			)
		)
	)
)
